FILE_TYPE = CONNECTIVITY;
{Allegro Design Entry HDL 17.2-2016 S081 (4005846) 1/11/2022}
"PAGE_NUMBER" = 159;
0"NC";
END.
